# S9S_MB_2U (Grand Teton) — schematic netlist excerpt (pin names and nets, part order shuffled) for the footprints in the layout excerpt that follows; sources: Cadence DE-HDL packaged netlist, KiCad conversion of 03242023_DA0F0TMBIJ0_F0T_Motherboard_J_brd_V01_OCP.brd

R2975  Q_RES  1K 1% EMPTY  pkg 0402LF  page 195 : A = FAB_REV_ID1 ; B = GND
PR3992  Q_RES  0 5% CHIP  pkg 0402LF  page 303 : A = HSC_D_OC_3 ; B = HSC_D_OC_R

(kicad_pcb
	(version 20260206)
	(generator "pcbnew")
	(generator_version "10.0")
	(general
		(thickness 1.6)
		(legacy_teardrops no)
	)
	(paper "A4")
	(title_block
		(title "03242023_DA0F0TMBIJ0_F0T_Motherboard_J_brd_V01_OCP.brd")
		(comment 1 "Grand Teton / footprints 3276-3277 of 6105")
	)
	(layers
		(0 "F.Cu" signal "TOP")
		(4 "In1.Cu" signal "GND")
		(6 "In2.Cu" signal "IN1")
		(8 "In3.Cu" signal "GND1")
		(10 "In4.Cu" signal "IN2")
		(12 "In5.Cu" signal "GND2")
		(14 "In6.Cu" signal "IN3")
		(16 "In7.Cu" signal "GND3")
		(18 "In8.Cu" signal "VCC")
		(20 "In9.Cu" signal "VCC1")
		(22 "In10.Cu" signal "GND4")
		(24 "In11.Cu" signal "IN4")
		(26 "In12.Cu" signal "GND5")
		(28 "In13.Cu" signal "IN5")
		(30 "In14.Cu" signal "GND6")
		(32 "In15.Cu" signal "IN6")
		(34 "In16.Cu" signal "GND7")
		(2 "B.Cu" signal "BOTTOM")
		(9 "F.Adhes" user "F.Adhesive")
		(11 "B.Adhes" user "B.Adhesive")
		(13 "F.Paste" user "Package Geometry/Pastemask Top")
		(15 "B.Paste" user "Package Geometry/Pastemask Bottom")
		(5 "F.SilkS" user "Ref Des/Silkscreen Top")
		(7 "B.SilkS" user "Ref Des/Silkscreen Bottom")
		(1 "F.Mask" user "Board Geometry/Soldermask Top")
		(3 "B.Mask" user "Board Geometry/Soldermask Bottom")
		(17 "Dwgs.User" user "User.Drawings")
		(19 "Cmts.User" user "User.Comments")
		(21 "Eco1.User" user "User.Eco1")
		(23 "Eco2.User" user "User.Eco2")
		(25 "Edge.Cuts" user "Board Geometry/Outline")
		(27 "Margin" user)
		(31 "F.CrtYd" user "Package Geometry/Place Bound Top")
		(29 "B.CrtYd" user "Package Geometry/Place Bound Bottom")
		(35 "F.Fab" user "Ref Des/Assembly Top")
		(33 "B.Fab" user "Ref Des/Assembly Bottom")
	)
	(footprint ""
		(layer "F.Cu")
		(at 226.733608 -400.759422)
		(property "Reference" "PR3992"
			(at 0 0 0)
			(layer "F.SilkS")
			(hide yes)
			(effects
				(font
					(size 1.27 1.27)
				)
			)
		)
		(property "Value" ""
			(at 0 0 0)
			(layer "F.Fab")
			(effects
				(font
					(size 1.27 1.27)
				)
			)
		)
		(duplicate_pad_numbers_are_jumpers no)
		(fp_line
			(start -0.7874 -0.4064)
			(end 0.7874 -0.4064)
			(stroke
				(width 0.1524)
				(type default)
			)
			(layer "F.SilkS")
		)
		(fp_line
			(start -0.7874 0.4064)
			(end -0.7874 -0.4064)
			(stroke
				(width 0.1524)
				(type default)
			)
			(layer "F.SilkS")
		)
		(fp_line
			(start 0.7874 -0.4064)
			(end 0.7874 0.4064)
			(stroke
				(width 0.1524)
				(type default)
			)
			(layer "F.SilkS")
		)
		(fp_line
			(start 0.7874 0.4064)
			(end -0.7874 0.4064)
			(stroke
				(width 0.1524)
				(type default)
			)
			(layer "F.SilkS")
		)
		(fp_line
			(start -0.67945 -0.305054)
			(end -0.12065 -0.305054)
			(stroke
				(width 0.1)
				(type default)
			)
			(layer "F.Fab")
		)
		(fp_line
			(start -0.67945 0.3048)
			(end -0.67945 -0.305054)
			(stroke
				(width 0.1)
				(type default)
			)
			(layer "F.Fab")
		)
		(fp_line
			(start -0.12065 -0.305054)
			(end -0.12065 -0.2794)
			(stroke
				(width 0.1)
				(type default)
			)
			(layer "F.Fab")
		)
		(fp_line
			(start -0.12065 -0.2794)
			(end 0.12065 -0.2794)
			(stroke
				(width 0.1)
				(type default)
			)
			(layer "F.Fab")
		)
		(fp_line
			(start -0.12065 0.2794)
			(end -0.12065 0.3048)
			(stroke
				(width 0.1)
				(type default)
			)
			(layer "F.Fab")
		)
		(fp_line
			(start -0.12065 0.3048)
			(end -0.67945 0.3048)
			(stroke
				(width 0.1)
				(type default)
			)
			(layer "F.Fab")
		)
		(fp_line
			(start 0.120396 0.2794)
			(end -0.12065 0.2794)
			(stroke
				(width 0.1)
				(type default)
			)
			(layer "F.Fab")
		)
		(fp_line
			(start 0.120396 0.3048)
			(end 0.120396 0.2794)
			(stroke
				(width 0.1)
				(type default)
			)
			(layer "F.Fab")
		)
		(fp_line
			(start 0.12065 -0.3048)
			(end 0.67945 -0.3048)
			(stroke
				(width 0.1)
				(type default)
			)
			(layer "F.Fab")
		)
		(fp_line
			(start 0.12065 -0.2794)
			(end 0.12065 -0.3048)
			(stroke
				(width 0.1)
				(type default)
			)
			(layer "F.Fab")
		)
		(fp_line
			(start 0.67945 -0.3048)
			(end 0.67945 0.3048)
			(stroke
				(width 0.1)
				(type default)
			)
			(layer "F.Fab")
		)
		(fp_line
			(start 0.67945 0.3048)
			(end 0.120396 0.3048)
			(stroke
				(width 0.1)
				(type default)
			)
			(layer "F.Fab")
		)
		(pad "1" smd circle
			(at -0.40005 0)
			(size 0 0)
			(layers "F.Cu" "F.Mask" "F.Paste")
			(net "HSC_D_OC_3")
		)
		(pad "2" smd circle
			(at 0.40005 0)
			(size 0 0)
			(layers "F.Cu" "F.Mask" "F.Paste")
			(net "HSC_D_OC_R")
		)
	)
	(footprint ""
		(layer "F.Cu")
		(at 321.8561 -76.585064 90)
		(property "Reference" "R2975"
			(at 0 0 90)
			(layer "F.SilkS")
			(hide yes)
			(effects
				(font
					(size 1.27 1.27)
				)
			)
		)
		(property "Value" ""
			(at 0 0 90)
			(layer "F.Fab")
			(effects
				(font
					(size 1.27 1.27)
				)
			)
		)
		(duplicate_pad_numbers_are_jumpers no)
		(fp_line
			(start 0.7874 -0.4064)
			(end 0.7874 0.4064)
			(stroke
				(width 0.1524)
				(type default)
			)
			(layer "F.SilkS")
		)
		(fp_line
			(start -0.7874 -0.4064)
			(end 0.7874 -0.4064)
			(stroke
				(width 0.1524)
				(type default)
			)
			(layer "F.SilkS")
		)
		(fp_line
			(start 0.7874 0.4064)
			(end -0.7874 0.4064)
			(stroke
				(width 0.1524)
				(type default)
			)
			(layer "F.SilkS")
		)
		(fp_line
			(start -0.7874 0.4064)
			(end -0.7874 -0.4064)
			(stroke
				(width 0.1524)
				(type default)
			)
			(layer "F.SilkS")
		)
		(fp_line
			(start -0.12065 -0.305054)
			(end -0.12065 -0.2794)
			(stroke
				(width 0.1)
				(type default)
			)
			(layer "F.Fab")
		)
		(fp_line
			(start -0.67945 -0.305054)
			(end -0.12065 -0.305054)
			(stroke
				(width 0.1)
				(type default)
			)
			(layer "F.Fab")
		)
		(fp_line
			(start 0.67945 -0.3048)
			(end 0.67945 0.3048)
			(stroke
				(width 0.1)
				(type default)
			)
			(layer "F.Fab")
		)
		(fp_line
			(start 0.12065 -0.3048)
			(end 0.67945 -0.3048)
			(stroke
				(width 0.1)
				(type default)
			)
			(layer "F.Fab")
		)
		(fp_line
			(start 0.12065 -0.2794)
			(end 0.12065 -0.3048)
			(stroke
				(width 0.1)
				(type default)
			)
			(layer "F.Fab")
		)
		(fp_line
			(start -0.12065 -0.2794)
			(end 0.12065 -0.2794)
			(stroke
				(width 0.1)
				(type default)
			)
			(layer "F.Fab")
		)
		(fp_line
			(start 0.120396 0.2794)
			(end -0.12065 0.2794)
			(stroke
				(width 0.1)
				(type default)
			)
			(layer "F.Fab")
		)
		(fp_line
			(start -0.12065 0.2794)
			(end -0.12065 0.3048)
			(stroke
				(width 0.1)
				(type default)
			)
			(layer "F.Fab")
		)
		(fp_line
			(start 0.67945 0.3048)
			(end 0.120396 0.3048)
			(stroke
				(width 0.1)
				(type default)
			)
			(layer "F.Fab")
		)
		(fp_line
			(start 0.120396 0.3048)
			(end 0.120396 0.2794)
			(stroke
				(width 0.1)
				(type default)
			)
			(layer "F.Fab")
		)
		(fp_line
			(start -0.12065 0.3048)
			(end -0.67945 0.3048)
			(stroke
				(width 0.1)
				(type default)
			)
			(layer "F.Fab")
		)
		(fp_line
			(start -0.67945 0.3048)
			(end -0.67945 -0.305054)
			(stroke
				(width 0.1)
				(type default)
			)
			(layer "F.Fab")
		)
		(pad "1" smd circle
			(at -0.40005 0 90)
			(size 0 0)
			(layers "F.Cu" "F.Mask" "F.Paste")
			(net "FAB_REV_ID1")
		)
		(pad "2" smd circle
			(at 0.40005 0 90)
			(size 0 0)
			(layers "F.Cu" "F.Mask" "F.Paste")
			(net "GND")
		)
	)
)
